# S9S_MB_2U (Grand Teton) — schematic netlist excerpt (pin names and nets, part order shuffled) for the footprints in the layout excerpt that follows; sources: Cadence DE-HDL packaged netlist, KiCad conversion of 03242023_DA0F0TMBIJ0_F0T_Motherboard_J_brd_V01_OCP.brd

PR4241  Q_RES  499 1% CHIP  pkg 0402LF  page 289 : A = PVCCFA_EHV_FIVRA_CPU1 ; B = GND
R3897  Q_RES  49.9 1% CHIP  pkg 0402LF  page 104 : A = I3C_SPD_DDRABCD_CPU1_LVC1_SCL_6 ; B = I3C_SPD_DDRABCD_CPU1_LVC1_SCL

(kicad_pcb
	(version 20260206)
	(generator "pcbnew")
	(generator_version "10.0")
	(general
		(thickness 1.6)
		(legacy_teardrops no)
	)
	(paper "A4")
	(title_block
		(title "03242023_DA0F0TMBIJ0_F0T_Motherboard_J_brd_V01_OCP.brd")
		(comment 1 "Grand Teton / footprints 5802-5803 of 6105")
	)
	(layers
		(0 "F.Cu" signal "TOP")
		(4 "In1.Cu" signal "GND")
		(6 "In2.Cu" signal "IN1")
		(8 "In3.Cu" signal "GND1")
		(10 "In4.Cu" signal "IN2")
		(12 "In5.Cu" signal "GND2")
		(14 "In6.Cu" signal "IN3")
		(16 "In7.Cu" signal "GND3")
		(18 "In8.Cu" signal "VCC")
		(20 "In9.Cu" signal "VCC1")
		(22 "In10.Cu" signal "GND4")
		(24 "In11.Cu" signal "IN4")
		(26 "In12.Cu" signal "GND5")
		(28 "In13.Cu" signal "IN5")
		(30 "In14.Cu" signal "GND6")
		(32 "In15.Cu" signal "IN6")
		(34 "In16.Cu" signal "GND7")
		(2 "B.Cu" signal "BOTTOM")
		(9 "F.Adhes" user "F.Adhesive")
		(11 "B.Adhes" user "B.Adhesive")
		(13 "F.Paste" user "Package Geometry/Pastemask Top")
		(15 "B.Paste" user "Package Geometry/Pastemask Bottom")
		(5 "F.SilkS" user "Ref Des/Silkscreen Top")
		(7 "B.SilkS" user "Ref Des/Silkscreen Bottom")
		(1 "F.Mask" user "Board Geometry/Soldermask Top")
		(3 "B.Mask" user "Board Geometry/Soldermask Bottom")
		(17 "Dwgs.User" user "User.Drawings")
		(19 "Cmts.User" user "User.Comments")
		(21 "Eco1.User" user "User.Eco1")
		(23 "Eco2.User" user "User.Eco2")
		(25 "Edge.Cuts" user "Board Geometry/Outline")
		(27 "Margin" user)
		(31 "F.CrtYd" user "Package Geometry/Place Bound Top")
		(29 "B.CrtYd" user "Package Geometry/Place Bound Bottom")
		(35 "F.Fab" user "Ref Des/Assembly Top")
		(33 "B.Fab" user "Ref Des/Assembly Bottom")
	)
	(footprint ""
		(layer "B.Cu")
		(at 36.60648 -344.757248 -90)
		(property "Reference" "PR4241"
			(at 0 0 90)
			(layer "B.SilkS")
			(hide yes)
			(effects
				(font
					(size 1.27 1.27)
				)
				(justify mirror)
			)
		)
		(property "Value" ""
			(at 0 0 90)
			(layer "B.Fab")
			(effects
				(font
					(size 1.27 1.27)
				)
				(justify mirror)
			)
		)
		(duplicate_pad_numbers_are_jumpers no)
		(fp_line
			(start -0.7874 0.4064)
			(end 0.7874 0.4064)
			(stroke
				(width 0.1524)
				(type default)
			)
			(layer "B.SilkS")
		)
		(fp_line
			(start 0.7874 0.4064)
			(end 0.7874 -0.4064)
			(stroke
				(width 0.1524)
				(type default)
			)
			(layer "B.SilkS")
		)
		(fp_line
			(start -0.7874 -0.4064)
			(end -0.7874 0.4064)
			(stroke
				(width 0.1524)
				(type default)
			)
			(layer "B.SilkS")
		)
		(fp_line
			(start 0.7874 -0.4064)
			(end -0.7874 -0.4064)
			(stroke
				(width 0.1524)
				(type default)
			)
			(layer "B.SilkS")
		)
		(fp_line
			(start -0.67945 0.3048)
			(end -0.120396 0.3048)
			(stroke
				(width 0.1)
				(type default)
			)
			(layer "B.Fab")
		)
		(fp_line
			(start -0.120396 0.3048)
			(end -0.120396 0.2794)
			(stroke
				(width 0.1)
				(type default)
			)
			(layer "B.Fab")
		)
		(fp_line
			(start 0.12065 0.3048)
			(end 0.67945 0.3048)
			(stroke
				(width 0.1)
				(type default)
			)
			(layer "B.Fab")
		)
		(fp_line
			(start 0.67945 0.3048)
			(end 0.67945 -0.305054)
			(stroke
				(width 0.1)
				(type default)
			)
			(layer "B.Fab")
		)
		(fp_line
			(start -0.120396 0.2794)
			(end 0.12065 0.2794)
			(stroke
				(width 0.1)
				(type default)
			)
			(layer "B.Fab")
		)
		(fp_line
			(start 0.12065 0.2794)
			(end 0.12065 0.3048)
			(stroke
				(width 0.1)
				(type default)
			)
			(layer "B.Fab")
		)
		(fp_line
			(start -0.12065 -0.2794)
			(end -0.12065 -0.3048)
			(stroke
				(width 0.1)
				(type default)
			)
			(layer "B.Fab")
		)
		(fp_line
			(start 0.12065 -0.2794)
			(end -0.12065 -0.2794)
			(stroke
				(width 0.1)
				(type default)
			)
			(layer "B.Fab")
		)
		(fp_line
			(start -0.67945 -0.3048)
			(end -0.67945 0.3048)
			(stroke
				(width 0.1)
				(type default)
			)
			(layer "B.Fab")
		)
		(fp_line
			(start -0.12065 -0.3048)
			(end -0.67945 -0.3048)
			(stroke
				(width 0.1)
				(type default)
			)
			(layer "B.Fab")
		)
		(fp_line
			(start 0.12065 -0.305054)
			(end 0.12065 -0.2794)
			(stroke
				(width 0.1)
				(type default)
			)
			(layer "B.Fab")
		)
		(fp_line
			(start 0.67945 -0.305054)
			(end 0.12065 -0.305054)
			(stroke
				(width 0.1)
				(type default)
			)
			(layer "B.Fab")
		)
		(pad "1" smd circle
			(at 0.40005 0 90)
			(size 0 0)
			(layers "B.Cu" "B.Mask" "B.Paste")
			(net "PVCCFA_EHV_FIVRA_CPU1")
		)
		(pad "2" smd circle
			(at -0.40005 0 90)
			(size 0 0)
			(layers "B.Cu" "B.Mask" "B.Paste")
			(net "GND")
		)
	)
	(footprint ""
		(layer "B.Cu")
		(at 8.153146 -318.25311 180)
		(property "Reference" "R3897"
			(at 0 0 0)
			(layer "B.SilkS")
			(hide yes)
			(effects
				(font
					(size 1.27 1.27)
				)
				(justify mirror)
			)
		)
		(property "Value" ""
			(at 0 0 0)
			(layer "B.Fab")
			(effects
				(font
					(size 1.27 1.27)
				)
				(justify mirror)
			)
		)
		(duplicate_pad_numbers_are_jumpers no)
		(fp_line
			(start 0.7874 0.4064)
			(end 0.7874 -0.4064)
			(stroke
				(width 0.1524)
				(type default)
			)
			(layer "B.SilkS")
		)
		(fp_line
			(start 0.7874 -0.4064)
			(end -0.7874 -0.4064)
			(stroke
				(width 0.1524)
				(type default)
			)
			(layer "B.SilkS")
		)
		(fp_line
			(start -0.7874 0.4064)
			(end 0.7874 0.4064)
			(stroke
				(width 0.1524)
				(type default)
			)
			(layer "B.SilkS")
		)
		(fp_line
			(start -0.7874 -0.4064)
			(end -0.7874 0.4064)
			(stroke
				(width 0.1524)
				(type default)
			)
			(layer "B.SilkS")
		)
		(fp_line
			(start 0.67945 0.3048)
			(end 0.67945 -0.305054)
			(stroke
				(width 0.1)
				(type default)
			)
			(layer "B.Fab")
		)
		(fp_line
			(start 0.67945 -0.305054)
			(end 0.12065 -0.305054)
			(stroke
				(width 0.1)
				(type default)
			)
			(layer "B.Fab")
		)
		(fp_line
			(start 0.12065 0.3048)
			(end 0.67945 0.3048)
			(stroke
				(width 0.1)
				(type default)
			)
			(layer "B.Fab")
		)
		(fp_line
			(start 0.12065 0.2794)
			(end 0.12065 0.3048)
			(stroke
				(width 0.1)
				(type default)
			)
			(layer "B.Fab")
		)
		(fp_line
			(start 0.12065 -0.2794)
			(end -0.12065 -0.2794)
			(stroke
				(width 0.1)
				(type default)
			)
			(layer "B.Fab")
		)
		(fp_line
			(start 0.12065 -0.305054)
			(end 0.12065 -0.2794)
			(stroke
				(width 0.1)
				(type default)
			)
			(layer "B.Fab")
		)
		(fp_line
			(start -0.120396 0.3048)
			(end -0.120396 0.2794)
			(stroke
				(width 0.1)
				(type default)
			)
			(layer "B.Fab")
		)
		(fp_line
			(start -0.120396 0.2794)
			(end 0.12065 0.2794)
			(stroke
				(width 0.1)
				(type default)
			)
			(layer "B.Fab")
		)
		(fp_line
			(start -0.12065 -0.2794)
			(end -0.12065 -0.3048)
			(stroke
				(width 0.1)
				(type default)
			)
			(layer "B.Fab")
		)
		(fp_line
			(start -0.12065 -0.3048)
			(end -0.67945 -0.3048)
			(stroke
				(width 0.1)
				(type default)
			)
			(layer "B.Fab")
		)
		(fp_line
			(start -0.67945 0.3048)
			(end -0.120396 0.3048)
			(stroke
				(width 0.1)
				(type default)
			)
			(layer "B.Fab")
		)
		(fp_line
			(start -0.67945 -0.3048)
			(end -0.67945 0.3048)
			(stroke
				(width 0.1)
				(type default)
			)
			(layer "B.Fab")
		)
		(pad "1" smd circle
			(at 0.40005 0)
			(size 0 0)
			(layers "B.Cu" "B.Mask" "B.Paste")
			(net "I3C_SPD_DDRABCD_CPU1_LVC1_SCL_6")
		)
		(pad "2" smd circle
			(at -0.40005 0)
			(size 0 0)
			(layers "B.Cu" "B.Mask" "B.Paste")
			(net "I3C_SPD_DDRABCD_CPU1_LVC1_SCL")
		)
	)
)
